# S9S_MB_2U (Grand Teton) — schematic parts with pin connectivity, parts 5927–5971 of 6093; source: Cadence DE-HDL packaged netlist (pstxprt.dat, pstxnet.dat, pstchip.dat)

U96  NX3L2267GM  IC  pkg XQFN10  page 239
  1  \1y0\  BI  = JTAG_BMC_PLD_TDI
  2  \1y1\  BI  = JTAG_BMC_DBP_TDI
  3  \2y0\  BI  = JTAG_BMC_PLD_TDO
  4  \2y1\  BI  = JTAG_BMC_DBP_TDO
  5  GND  POWER  = GND
  6  \2z\  BI  = JTAG_BMC_SW_TDO
  7  \2s\  IN  = FM_JTAG_BMC_MUX_SEL
  8  \1s\  IN  = FM_JTAG_BMC_MUX_SEL
  9  \1z\  BI  = JTAG_BMC_SW_TDI
  10  VCC  POWER  = P3V3_AUX

U97  NX3L2267GM  IC  pkg XQFN10  page 239
  1  \1y0\  BI  = JTAG_BMC_PLD_TMS
  2  \1y1\  BI  = JTAG_BMC_DBP_TMS
  3  \2y0\  BI  = JTAG_BMC_PLD_TCK
  4  \2y1\  BI  = JTAG_BMC_DBP_TCK
  5  GND  POWER  = GND
  6  \2z\  BI  = JTAG_BMC_SW_TCK
  7  \2s\  IN  = FM_JTAG_BMC_MUX_SEL
  8  \1s\  IN  = FM_JTAG_BMC_MUX_SEL
  9  \1z\  BI  = JTAG_BMC_SW_TMS
  10  VCC  POWER  = P3V3_AUX

U98  PCA9306DP1  IC  pkg TSSOP8_3  page 194
  1  GND  POWER  = GND
  2  VREF1  POWER  = P1V8_PCH_AUX
  3  SCL1  BI  = SMB_M2_P0_1V8AUX_SCL_R
  4  SDA1  BI  = SMB_M2_P0_1V8AUX_SDA_R
  5  SDA2  BI  = SMB_SENSOR_M2_P0_3V3AUX_SDA
  6  SCL2  BI  = SMB_SENSOR_M2_P0_3V3AUX_SCL
  7  VREF2  POWER  = SMB_PCIE_M2_0_EN
  8  EN  IN  = SMB_PCIE_M2_0_EN

U99  RT9818C44GV  RT9818C-44GV IC  pkg SOT23_123_2-89X1-6  page 260
  1  \reset#\  OUT  = PWRGD_P5V
  2  GND  POWER  = GND
  3  VDD  POWER  = P5V

U102  INA183A1IDBVR  EMPTY  pkg SOT23-5_0-95_2-9X1-6XD  page 251
  1  GND0  POWER  = GND
  2  GND1  POWER  = GND
  3  \out\  OUT  = PVCCD_HV_CPU0_NVDIMM_ISENSE
  4  \in-\  IN  = P12V_AUX_CPU0_DIMM_ISEN_N
  5  \in+\  IN  = P12V_AUX_CPU0_DIMM_ISEN_P

U103  INA183A1IDBVR  EMPTY  pkg SOT23-5_0-95_2-9X1-6XD  page 251
  1  GND0  POWER  = GND
  2  GND1  POWER  = GND
  3  \out\  OUT  = PVCCD_HV_CPU1_NVDIMM_ISENSE
  4  \in-\  IN  = P12V_AUX_CPU1_DIMM_ISEN_N
  5  \in+\  IN  = P12V_AUX_CPU1_DIMM_ISEN_P

U104  74LVC1G07GV  IC  pkg SC-74A_2-9X1-5  page 155
  1  NC1  TRI  = NC_U104_NC1
  2  A  IN  = FM_SYS_THROTTLE_R_N
  3  GND  POWER  = GND
  4  Y  OCA  = OCP_SFF_PWRBRK_BUFF_N
  5  VCC  POWER  = P3V3_AUX

U117  TPS3895ADRYR  EMPTY  pkg SON6  page 244
  1  ENABLE  IN  = FM_COMP_P3V3_AUX_ENIN
  2  GND  POWER  = GND
  3  SENSE  BI  = FM_COMP_P3V3_AUX_VIN
  4  SENSE_OUT  OCA  = PWRGD_DSW_PWROK_R1
  5  CT  BI  = FM_COMP_P3V3_STBY_CEXT
  6  VCC  POWER  = P3V3_AUX

U134  74LVC2G07DW7  74LVC2G07DW-7 IC  pkg SOT363_0-65_2X1-25XC  page 191
  1  \1a\  IN  = RST_SMB_E1S_N
  2  GND  POWER  = GND
  3  \2a\  IN  = RST_SMB_E1S_N
  4  \2y\  OUT  = SMB_PCIE_E1S_ISO_EN_R2
  5  VCC  POWER  = P3V3_AUX
  6  \1y\  OUT  = RST_SMB_BUF_E1S_0_N

U142  NC7SB3157  NC7SB3157P6X IC  pkg SMLF  page 197
  1  B1  BI  = PECI_BMC_B1
  2  GND  POWER  = GND
  3  B0  BI  = PECI_PCH_B1
  4  A  BI  = PECI_CPU_GTL
  5  VCC  POWER  = P3V3_AUX
  6  S  IN  = PECI_MUX_SEL_R

U143  PCA9545APW  IC  pkg TSSOP20_0-65_6-5X4-4  page 236
  1  A0  IN  = PCA9543_S3M_ADDR0
  2  A1  IN  = PCA9543_S3M_ADDR1
  3  \reset#\  IN  = RST_SMB_S3M_N
  4  \int0#\  IN  = PCA9543_S3M_INT0_N
  5  SD0  BI  = SMB_S3M_CPU0_3V3AUX_SDA_R
  6  SC0  IN  = SMB_S3M_CPU0_3V3AUX_SCL_R
  7  \int1#\  IN  = PCA9543_S3M_INT1_N
  8  SD1  BI  = SMB_S3M_CPU1_3V3AUX_SDA_R
  9  SC1  IN  = SMB_S3M_CPU1_3V3AUX_SCL_R
  10  VSS  POWER  = GND
  11  \int2#\  IN  = PCA9543_S3M_INT2_N
  12  SD2  BI  = SMB_S3M_CPU0_PIROM_3V3AUX_SDA_R
  13  SC2  IN  = SMB_S3M_CPU0_PIROM_3V3AUX_SCL_R
  14  \int3#\  IN  = PCA9543_S3M_INT3_N
  15  SD3  BI  = SMB_S3M_CPU1_PIROM_3V3AUX_SDA_R
  16  SC3  IN  = SMB_S3M_CPU1_PIROM_3V3AUX_SCL_R
  17  \int#\  OUT  = PCA9545_S3M_INT_N
  18  SCL  IN  = SMB_S3M_CPU_3V3AUX_SCL
  19  SDA  BI  = SMB_S3M_CPU_3V3AUX_SDA
  20  VDD  POWER  = P3V3_AUX

U145  74LVC1G126SE7  74LVC1G126SE-7 IC  pkg SOT353_0-65_2X1-25  page 191
  1  OE  IN  = FM_PS_EN_PLD_BUF1_R1
  2  A  IN  = E1S_0_PRSNT
  3  GND  POWER  = GND
  4  Y  OUT  = E1S_0_EN
  5  VCC  POWER  = P3V3_AUX

U150  74LVC2G17GW  IC  pkg SOT363  page 224
  1  A0  IN  = FM_PS_EN_PLD_R
  2  GND  POWER  = GND
  3  A1  IN  = NC_U150_A1
  4  B1  OUT  = NC_U150_B1
  5  VCC  POWER  = P3V3_AUX
  6  B0  OUT  = FM_PS_EN_PLD_BUF1

U154  74LVC1G07SE7  74LVC1G07SE-7 IC  pkg SOT353_0-65_2X1-25  page 202
  1  NC1  TRI  = NC_ESPI_PLD_R_EN_BUF
  2  A  IN  = FM_ESPI_PLD_R1_EN
  3  GND  POWER  = GND
  4  Y  OUT  = FM_ESPI_PLD_R_EN_BUF
  5  VCC  POWER  = P3V3_AUX

U157  74LVC1G07GV  IC  pkg SC-74A_2-9X1-5  page 155
  1  NC1  TRI  = NC_U157_NC1
  2  A  IN  = OCP_SFF_WAKE_BUFF_R_N
  3  GND  POWER  = GND
  4  Y  OCA  = IRQ_LVC3_WAKE_BUF_N
  5  VCC  POWER  = P3V3_AUX

U158  MOSFET_NCH_GDS_ESD_PROTECTED  2N7002K IC  pkg SOT23_GDSXC  page 247
  D  D  BI  = FM_P12V_HSC_EN_N
  G  G  IN  = FM_P12V_HSC_EN_R
  S  S  BI  = GND

U175  LTC4307CMS8  IC  pkg MSOP8  page 234
  1  ENABLE  IN  = SMB_BMC_SWB_EN_R
  2  SCL_OUT  BI  = SMB_BMC_SWB_BUF_R_SCL
  3  SCL_IN  BI  = SMB_BMC_SWB_R_SCL
  4  GND  POWER  = GND
  5  READY  OUT  = NC
  6  SDA_IN  BI  = SMB_BMC_SWB_R_SDA
  7  SDA_OUT  BI  = SMB_BMC_SWB_BUF_R_SDA
  8  VCC  POWER  = P3V3_AUX

U176  LTC4307CMS8  EMPTY  pkg MSOP8  page 234
  1  ENABLE  IN  = SMB_BMC_SWB_EN_R2
  2  SCL_OUT  BI  = I3C_BMC_SWB_BUF_R_SCL
  3  SCL_IN  BI  = I3C_BMC_SWB_R_SCL
  4  GND  POWER  = GND
  5  READY  OUT  = NC
  6  SDA_IN  BI  = I3C_BMC_SWB_R_SDA
  7  SDA_OUT  BI  = I3C_BMC_SWB_BUF_R_SDA
  8  VCC  POWER  = P3V3_AUX

U181  PCA9539RPW  IC  pkg TSSOP24XB  page 227
  1  INT  BI  = PU_U181_INT
  2  A1  IN  = TCA9539_0_ADD1
  3  RESET  BI  = PU_RST_SMB_U181_N
  4  IO0_0  BI  = RST_USB_HUB_N
  5  IO0_1  BI  = RST_SWB_BIC_N
  6  IO0_2  BI  = TP_TCA9539_0_P0_2
  7  IO0_3  BI  = TP_TCA9539_0_P0_3
  8  IO0_4  BI  = PRSNT_SWB_ISO_R1_N
  9  IO0_5  BI  = GPU_PRSNT_N_ISO_R1
  10  IO0_6  BI  = PRSNT_CABLE_GPU_B3_ISO_R1_N
  11  IO0_7  BI  = PRSNT_CABLE_SWB_B2_ISO_R_N
  12  VSS  POWER  = GND
  13  IO1_0  BI  = PRSNT_CABLE_GPU_A2_ISO_R1_N
  14  IO1_1  BI  = PRSNT_CABLE_SWB_B1_ISO_R_N
  15  IO1_2  BI  = GPU_BASE_ID0_R
  16  IO1_3  BI  = GPU_BASE_ID1_R
  17  IO1_4  BI  = GPU_PEX_STRAP0_R
  18  IO1_5  BI  = GPU_PEX_STRAP1_R
  19  IO1_6  BI  = PRSNT_CABLE_GPU_A1_ISO_R1_N
  20  IO1_7  BI  = PRSNT_CABLE_GPU_A3_ISO_R_N
  21  A0  IN  = TCA9539_0_ADD0
  22  SCL  BI  = SMB_IOEXP_3V3AUX_SCL_R1
  23  SDA  BI  = SMB_IOEXP_3V3AUX_SDA_R1
  24  VDD  POWER  = P3V3_AUX

U192  LTC4307CMS8  IC  pkg MSOP8  page 245
  1  ENABLE  IN  = FM_MB_PDB_SMB9_R_EN
  2  SCL_OUT  BI  = SMB_FAN_3V3AUX_BUF_SCL
  3  SCL_IN  BI  = SMB_FAN_3V3AUX_R_SCL
  4  GND  POWER  = GND
  5  READY  OUT  = NC
  6  SDA_IN  BI  = SMB_FAN_3V3AUX_R_SDA
  7  SDA_OUT  BI  = SMB_FAN_3V3AUX_BUF_SDA
  8  VCC  POWER  = P3V3_AUX

U193  MAX11617EEET  MAX11617EEE+T EMPTY  pkg QSOP16_0-635_4-9X3-89  page 250
  1  \ain11||ref\  BI  = MAX11617_VREF_R
  2  AIN10  BI  = GND
  3  AIN9  BI  = GND
  4  AIN8  BI  = GND
  5  AIN0  BI  = P12V_AUX_ADC_MAM
  6  AIN1  BI  = P12V_OCP_SFF_ISENSE_MAM
  7  AIN2  BI  = P12V_OCP_V3_2_ISENSE_MAM
  8  AIN3  BI  = P5V_ADC_MAM
  9  AIN4  BI  = P3V3_ADC_MAM
  10  AIN5  BI  = P3V3_AUX_ADC_MAM
  11  AIN6  BI  = P3V3_PDB_AUX_ADC_MAM
  12  AIN7  BI  = P12V_E1S_0_ISENSE_MAM
  13  SCL  BI  = SMB_SEN_MAM_3V3AUX_SCL
  14  SDA  BI  = SMB_SEN_MAM_3V3AUX_SDA
  15  GND  POWER  = GND
  16  VDD  POWER  = P3V3_MAX11617_VDD

U194  LTC4307CMS8  IC  pkg MSOP8  page 234
  1  ENABLE  IN  = SMB_BMC_GPU_EN_R1
  2  SCL_OUT  BI  = SMB_1_BMC_GPU_BUF_R_SCL
  3  SCL_IN  BI  = SMB_1_BMC_GPU_R_SCL
  4  GND  POWER  = GND
  5  READY  OUT  = NC
  6  SDA_IN  BI  = SMB_1_BMC_GPU_R_SDA
  7  SDA_OUT  BI  = SMB_1_BMC_GPU_BUF_R_SDA
  8  VCC  POWER  = P3V3_AUX

U195  74LVC2G17GW  IC  pkg SOT363  page 151
  1  A0  IN  = BMC_MONITER_R
  2  GND  POWER  = GND
  3  A1  IN  = RST_SWB_BIC_R_N
  4  B1  OUT  = RST_SWB_BIC_BUF_R_N
  5  VCC  POWER  = P3V3_AUX
  6  B0  OUT  = BMC_MONITER_BUF_R

U196  74LVC2G17GW  IC  pkg SOT363  page 151
  1  A0  IN  = FM_GPU_PWR_EN_R
  2  GND  POWER  = GND
  3  A1  IN  = GPU_FPGA_RST_R_N
  4  B1  OUT  = GPU_FPGA_RST_R1_BUF_N
  5  VCC  POWER  = P3V3_AUX
  6  B0  OUT  = FM_GPU_PWR_EN_R1

U200  LTC4307CMS8  IC  pkg MSOP8  page 234
  1  ENABLE  IN  = SMB_BMC_GPU_EN_R3
  2  SCL_OUT  BI  = SMB_2_BMC_GPU_BUF_R_SCL
  3  SCL_IN  BI  = SMB_2_BMC_GPU_R_SCL
  4  GND  POWER  = GND
  5  READY  OUT  = NC
  6  SDA_IN  BI  = SMB_2_BMC_GPU_R_SDA
  7  SDA_OUT  BI  = SMB_2_BMC_GPU_BUF_R_SDA
  8  VCC  POWER  = P3V3_AUX

U204  74LVC1G126SE7  74LVC1G126SE-7 IC  pkg SOT353_0-65_2X1-25  page 151
  1  OE  IN  = FM_UART_EN
  2  A  IN  = UART_BMC_BIC_R_RX
  3  GND  POWER  = GND
  4  Y  OUT  = UART_BMC_BIC_R_BUF_RX
  5  VCC  POWER  = P3V3_AUX

U205  TPS3700DDCR  EMPTY  pkg SOT23-6XF  page 306
  1  OUTA  OUT  = PWRGD_DSW_PWROK_R4
  2  GND  POWER  = GND
  3  \ina+\  IN  = A_HSC_INAP
  4  \inb-\  IN  = NC_U205_INB-
  5  VDD  POWER  = U205_VDD
  6  OUTB  OUT  = NC_U205_OUTB

U206  LT6700CS61TRPBF  LT6700CS6-1#TRPBF IC  pkg TSOT23-6_0-95_2-9X1-625  page 306
  1  OUTA  OUT  = FM_UV_ADR_TRIGGER_N
  2  GND  POWER  = GND
  3  \ina+\  IN  = A_P12V_STBY_ADR_TRIGGER
  4  \inb-\  IN  = A_P12V_STBY_FP_TRIGGER
  5  VS  POWER  = U206_VDD
  6  OUTB  OUT  = A_P12V_STBY_FPH_GATE

U207  74LVC1G17GW  IC  pkg TSSOP5  page 161
  1  NC  TRI  = NC
  2  A  IN  = RST_HP_OCP_V3_2_N
  3  GND  POWER  = GND
  4  Y  OCA  = RST_OCP_V3_2_BUF_N
  5  VCC  POWER  = P3V3_AUX

U208  74LVC1G08W57  74LVC1G08W5-7 IC  pkg SOT25-5_0-95_3X1-6  page 158
  1  A  IN  = HP_OCP_V3_1_EN
  2  B  IN  = HP_LVC3_OCP_V3_1_PRSNT2
  3  GND  POWER  = GND
  4  Y  OUT  = HP_LVC3_OCP_V3_1_EN
  5  VCC  POWER  = P3V3_AUX

U209  PCA9555APW  IC  pkg TSSOP24XB  page 158
  1  \int#\  OUT  = FM_SMB_CPU0_ALERT
  2  A1  IN  = PD_SMB_OCP1_HP_ADD1
  3  A2  IN  = PD_SMB_OCP1_HP_ADD2
  4  P0_0  BI  = TP_PCA9555_0_P00
  5  P0_1  BI  = TP_PCA9555_0_P01
  6  P0_2  BI  = HP_OCP_V3_1_EN
  7  P0_3  BI  = HP_LVC3_OCP_V3_1_ATTN_OUT_SW_N
  8  P0_4  BI  = HP_LVC3_OCP_V3_1_PRSNT2_N
  9  P0_5  BI  = TP_PCA9555_0_P5
  10  P0_6  BI  = TP_PCA9555_0_P6
  11  P0_7  BI  = TP_PCA9555_0_P7
  12  VSS  POWER  = GND
  13  P1_0  BI  = TP_PCA9555_0_P10
  14  P1_1  BI  = TP_PCA9555_0_P11
  15  P1_2  BI  = TP_PCA9555_0_P12
  16  P1_3  BI  = TP_PCA9555_0_P13
  17  P1_4  BI  = TP_PCA9555_0_P14
  18  P1_5  BI  = TP_PCA9555_0_P15
  19  P1_6  BI  = TP_PCA9555_0_P16
  20  P1_7  BI  = TP_PCA9555_0_P17
  21  A0  IN  = PD_SMB_OCP1_HP_ADD0
  22  SCL  IN  = SMB_PEHPCPU0_LVC3_R_SCL
  23  SDA  BI  = SMB_PEHPCPU0_LVC3_R_SDA
  24  VDD  POWER  = P3V3_AUX

U210  74LVC1G08W57  74LVC1G08W5-7 IC  pkg SOT25-5_0-95_3X1-6  page 158
  1  A  IN  = HP_LVC3_OCP_V3_1_PWRGD_R
  2  B  IN  = RST_OCP_V3_1_N
  3  GND  POWER  = GND
  4  Y  OUT  = RST_HP_OCP_V3_1_N
  5  VCC  POWER  = P3V3_AUX

U211  74LVC2G07DW7  74LVC2G07DW-7 IC  pkg SOT363_0-65_2X1-25XC  page 156
  1  \1a\  IN  = OCP_SFF_PRSNT0_R_N
  2  GND  POWER  = GND
  3  \2a\  IN  = OCP_SFF_PRSNT1_R_N
  4  \2y\  OUT  = HP_LVC3_OCP_V3_1_PRSNT2_N_R
  5  VCC  POWER  = P3V3_AUX
  6  \1y\  OUT  = HP_LVC3_OCP_V3_1_PRSNT2_N_R

U212  74LVC2G07DW7  74LVC2G07DW-7 IC  pkg SOT363_0-65_2X1-25XC  page 156
  1  \1a\  IN  = OCP_SFF_PRSNT2_R_N
  2  GND  POWER  = GND
  3  \2a\  IN  = OCP_SFF_PRSNT3_R_N
  4  \2y\  OUT  = HP_LVC3_OCP_V3_1_PRSNT2_N_R
  5  VCC  POWER  = P3V3_AUX
  6  \1y\  OUT  = HP_LVC3_OCP_V3_1_PRSNT2_N_R

U215  MOSFET_N  BSS138K IC  pkg SMLF  page 164
  D  DRAIN  OUT  = HP_LVC3_OCP_V3_2_PRSNT2
  G  GATE  IN  = HP_LVC3_OCP_V3_2_PRSNT2_N
  S  SOURCE  BI  = GND

U216  APX80929SAG7  APX809-29SAG-7 IC  pkg SOT23_123XI  page 164
  1  GND  POWER  = GND
  2  RESET_L  OUT  = HP_OCP_V3_2_RST
  3  VCC  POWER  = P3V3_OCP_V3_2

U217  74LVC1G126SE7  74LVC1G126SE-7 IC  pkg SOT353_0-65_2X1-25  page 161
  1  OE  IN  = PU_OCP_V3_2_WAKE_OE
  2  A  IN  = IRQ_LVC3_OCP_V3_2_WAKE_N
  3  GND  POWER  = GND
  4  Y  OUT  = OCP_V3_2_WAKE_BUFF_N
  5  VCC  POWER  = P3V3_AUX

U218  74LVC1G07GV  IC  pkg SC-74A_2-9X1-5  page 161
  1  NC1  TRI  = NC_U218_NC1
  2  A  IN  = FM_SYS_THROTTLE_R_N
  3  GND  POWER  = GND
  4  Y  OCA  = OCP_V3_2_PWRBRK_BUFF_N
  5  VCC  POWER  = P3V3_AUX

U219  74LVC1G07GV  IC  pkg SC-74A_2-9X1-5  page 161
  1  NC1  TRI  = NC_U219_NC1
  2  A  IN  = OCP_V3_2_WAKE_BUFF_R_N
  3  GND  POWER  = GND
  4  Y  OCA  = IRQ_LVC3_V3_2_WAKE_BUF_N
  5  VCC  POWER  = P3V3_AUX

U222  74CBTLV3126PW  IC  pkg TSSOP14  page 160
  1  \1oe\  IN  = FB_BMC_ISOLATE1
  2  \1a\  POWER  = NCSI_BMC_RXD1_R1
  3  \1b\  BI  = NCSI_OCP_V3_2_RXD1
  4  \2oe\  OUT  = FB_BMC_ISOLATE1
  5  \2a\  BI  = NCSI_BMC_RXD0_R1
  6  \2b\  BI  = NCSI_OCP_V3_2_RXD0
  7  GND  POWER  = GND
  8  \3b\  BI  = NCSI_OCP_V3_2_CRS_DV
  9  \3a\  BI  = NCSI_BMC_CRS_DV_R1
  10  \3oe\  BI  = FB_BMC_ISOLATE1
  11  \4b\  BI  = OCP_V3_2_ISO1_RBT_ARB_IN
  12  \4a\  BI  = OCP_V3_2_RBT_ARB_IN_R
  13  \4oe\  BI  = FB_BMC_ISOLATE1
  14  VCC  BI  = P3V3_AUX

U223  74CBTLV3126PW  IC  pkg TSSOP14  page 160
  1  \1oe\  IN  = FB_BMC_ISOLATE1
  2  \1a\  POWER  = NCSI_BMC_TXD1_R1
  3  \1b\  BI  = NCSI_OCP_V3_2_TXD1
  4  \2oe\  OUT  = FB_BMC_ISOLATE1
  5  \2a\  BI  = NCSI_BMC_TXD0_R1
  6  \2b\  BI  = NCSI_OCP_V3_2_TXD0
  7  GND  POWER  = GND
  8  \3b\  BI  = NCSI_OCP_V3_2_TX_EN
  9  \3a\  BI  = NCSI_BMC_TX_EN_R1
  10  \3oe\  BI  = FB_BMC_ISOLATE1
  11  \4b\  BI  = OCP_V3_2_ISO2_RBT_ARB_OUT
  12  \4a\  BI  = OCP_V3_2_RBT_ARB_OUT
  13  \4oe\  BI  = FB_BMC_ISOLATE1
  14  VCC  BI  = P3V3_AUX

U224  74LVC1G126SE7  74LVC1G126SE-7 IC  pkg SOT353_0-65_2X1-25  page 154
  1  OE  IN  = OCP_SFF_AUX_PWR_EN_R4
  2  A  IN  = RST_SMB_SWITCH_N
  3  GND  POWER  = GND
  4  Y  OUT  = RST_HP_OCP_SFF_R_N
  5  VCC  POWER  = P3V3_AUX

U225  74LVC1G126SE7  74LVC1G126SE-7 IC  pkg SOT353_0-65_2X1-25  page 161
  1  OE  IN  = OCP_V3_2_AUX_PWR_EN_R3
  2  A  IN  = RST_SMB_SWITCH_N
  3  GND  POWER  = GND
  4  Y  OUT  = RST_HP_OCP_V3_2_R_N
  5  VCC  POWER  = P3V3_AUX

U235  PCA9617ADP  IC  pkg TSSOP8_3XB  page 238
  1  VCCA  POWER  = P3V3_AUX
  2  SCLA  BI  = SMB_OCP_V3_2_3V3AUX_SCL
  3  SDAA  BI  = SMB_OCP_V3_2_3V3AUX_SDA
  4  GND  POWER  = GND
  5  EN  IN  = HP_LVC3_OCP_V3_2_R_EN
  6  SDAB  BI  = SMB_OCP_V3_2_3V3AUX_BUF_SDA
  7  SCLB  BI  = SMB_OCP_V3_2_3V3AUX_BUF_SCL
  8  VCCB  POWER  = P3V3_OCP_V3_2

U236  PCA9617ADP  IC  pkg TSSOP8_3XB  page 238
  1  VCCA  POWER  = P3V3_AUX
  2  SCLA  BI  = SMB_OCP_SFF_3V3AUX_SCL
  3  SDAA  BI  = SMB_OCP_SFF_3V3AUX_SDA
  4  GND  POWER  = GND
  5  EN  IN  = HP_LVC3_OCP_V3_1_R_EN
  6  SDAB  BI  = SMB_OCP_SFF_3V3AUX_BUF_SDA
  7  SCLB  BI  = SMB_OCP_SFF_3V3AUX_BUF_SCL
  8  VCCB  POWER  = P3V3_OCP_SFF
